(kicad_pcb
	(version 20260206)
	(generator "pcbnew")
	(generator_version "10.0")
	(general
		(thickness 1.6)
		(legacy_teardrops no)
	)
	(paper "A4")
	(title_block
		(title "04192023_DAF0TMB3IC0_F0TG_MB_C_brd_V02_OCP.brd")
		(comment 1 "Grand Teton / footprints 6232-6239 of 8354")
	)
	(layers
		(0 "F.Cu" signal "TOP")
		(4 "In1.Cu" signal "GND")
		(6 "In2.Cu" signal "IN1")
		(8 "In3.Cu" signal "GND1")
		(10 "In4.Cu" signal "IN2")
		(12 "In5.Cu" signal "GND2")
		(14 "In6.Cu" signal "IN3")
		(16 "In7.Cu" signal "GND3")
		(18 "In8.Cu" signal "VCC")
		(20 "In9.Cu" signal "VCC1")
		(22 "In10.Cu" signal "GND4")
		(24 "In11.Cu" signal "IN4")
		(26 "In12.Cu" signal "GND5")
		(28 "In13.Cu" signal "IN5")
		(30 "In14.Cu" signal "GND6")
		(32 "In15.Cu" signal "IN6")
		(34 "In16.Cu" signal "GND7")
		(2 "B.Cu" signal "BOTTOM")
		(9 "F.Adhes" user "F.Adhesive")
		(11 "B.Adhes" user "B.Adhesive")
		(13 "F.Paste" user "Package Geometry/Pastemask Top")
		(15 "B.Paste" user "Package Geometry/Pastemask Bottom")
		(5 "F.SilkS" user "Ref Des/Silkscreen Top")
		(7 "B.SilkS" user "Ref Des/Silkscreen Bottom")
		(1 "F.Mask" user "Board Geometry/Soldermask Top")
		(3 "B.Mask" user "Board Geometry/Soldermask Bottom")
		(17 "Dwgs.User" user "User.Drawings")
		(19 "Cmts.User" user "User.Comments")
		(21 "Eco1.User" user "User.Eco1")
		(23 "Eco2.User" user "User.Eco2")
		(25 "Edge.Cuts" user "Board Geometry/Outline")
		(27 "Margin" user)
		(31 "F.CrtYd" user "Package Geometry/Place Bound Top")
		(29 "B.CrtYd" user "Package Geometry/Place Bound Bottom")
		(35 "F.Fab" user "Ref Des/Assembly Top")
		(33 "B.Fab" user "Ref Des/Assembly Bottom")
	)
	(footprint ""
		(layer "B.Cu")
		(at 325.910448 -328.240644 -90)
		(property "Reference" "PC102"
			(at 10.105644 -1.341882 270)
			(unlocked yes)
			(layer "B.SilkS")
			(effects
				(font
					(size 0.7874 0.5842)
					(thickness 0.1524)
				)
				(justify left mirror)
			)
		)
		(property "Value" ""
			(at 0 0 90)
			(layer "B.Fab")
			(effects
				(font
					(size 1.27 1.27)
				)
				(justify mirror)
			)
		)
		(duplicate_pad_numbers_are_jumpers no)
		(fp_line
			(start -4.533392 2.249932)
			(end 4.533392 2.249932)
			(stroke
				(width 0.1524)
				(type default)
			)
			(layer "B.SilkS")
		)
		(fp_line
			(start 4.533392 2.249932)
			(end 4.533392 -2.249932)
			(stroke
				(width 0.1524)
				(type default)
			)
			(layer "B.SilkS")
		)
		(fp_line
			(start -4.533392 -2.249932)
			(end -4.533392 2.249932)
			(stroke
				(width 0.1524)
				(type default)
			)
			(layer "B.SilkS")
		)
		(fp_line
			(start 4.533392 -2.249932)
			(end -4.533392 -2.249932)
			(stroke
				(width 0.1524)
				(type default)
			)
			(layer "B.SilkS")
		)
		(fp_rect
			(start 5.39242 2.326132)
			(end 4.533392 -2.326132)
			(stroke
				(width 0)
				(type default)
			)
			(fill yes)
			(layer "B.SilkS")
		)
		(fp_line
			(start -3.750056 2.249932)
			(end 3.750056 2.249932)
			(stroke
				(width 0.1)
				(type default)
			)
			(layer "B.Fab")
		)
		(fp_line
			(start 3.750056 2.249932)
			(end 3.750056 -2.249932)
			(stroke
				(width 0.1)
				(type default)
			)
			(layer "B.Fab")
		)
		(fp_line
			(start -3.750056 -2.249932)
			(end -3.750056 2.249932)
			(stroke
				(width 0.1)
				(type default)
			)
			(layer "B.Fab")
		)
		(fp_line
			(start 3.750056 -2.249932)
			(end -3.750056 -2.249932)
			(stroke
				(width 0.1)
				(type default)
			)
			(layer "B.Fab")
		)
		(fp_text user "+"
			(at 6.294374 0.137922 180)
			(unlocked yes)
			(layer "B.SilkS")
			(effects
				(font
					(size 1.905 1.4224)
					(thickness 0.1524)
				)
				(justify left mirror)
			)
		)
		(fp_text user "-"
			(at -4.8514 -0.14605 270)
			(unlocked yes)
			(layer "B.SilkS")
			(effects
				(font
					(size 1.905 1.4224)
					(thickness 0.1524)
				)
				(justify left mirror)
			)
		)
		(fp_text user "+"
			(at 6.322314 0.786384 180)
			(unlocked yes)
			(layer "B.Fab")
			(effects
				(font
					(size 1.905 1.4224)
					(thickness 0.1524)
				)
				(justify left mirror)
			)
		)
		(fp_text user "-"
			(at -4.8514 -0.14605 270)
			(unlocked yes)
			(layer "B.Fab")
			(effects
				(font
					(size 1.905 1.4224)
					(thickness 0.1524)
				)
				(justify left mirror)
			)
		)
		(pad "1" smd rect
			(at 3.199892 0 90)
			(size 2.413 2.8194)
			(layers "B.Cu" "B.Mask" "B.Paste")
			(net "PVDDCR_CPU1_P0")
		)
		(pad "2" smd rect
			(at -3.199892 0 90)
			(size 2.413 2.8194)
			(layers "B.Cu" "B.Mask" "B.Paste")
			(net "GND")
		)
	)
	(footprint ""
		(layer "B.Cu")
		(at 358.089454 -246.44731 -120)
		(property "Reference" "C2190"
			(at 0 0 60)
			(layer "B.SilkS")
			(hide yes)
			(effects
				(font
					(size 1.27 1.27)
				)
				(justify mirror)
			)
		)
		(property "Value" ""
			(at 0 0 60)
			(layer "B.Fab")
			(effects
				(font
					(size 1.27 1.27)
				)
				(justify mirror)
			)
		)
		(duplicate_pad_numbers_are_jumpers no)
		(fp_line
			(start 0.787516 0.406438)
			(end 0.787425 -0.40652)
			(stroke
				(width 0.1524)
				(type default)
			)
			(layer "B.SilkS")
		)
		(fp_line
			(start 0.787425 -0.40652)
			(end -0.787516 -0.406438)
			(stroke
				(width 0.1524)
				(type default)
			)
			(layer "B.SilkS")
		)
		(fp_line
			(start -0.787425 0.40652)
			(end 0.787516 0.406438)
			(stroke
				(width 0.1524)
				(type default)
			)
			(layer "B.SilkS")
		)
		(fp_line
			(start -0.787516 -0.406438)
			(end -0.787425 0.40652)
			(stroke
				(width 0.1524)
				(type default)
			)
			(layer "B.SilkS")
		)
		(fp_line
			(start 0.679568 0.304811)
			(end 0.679373 -0.305128)
			(stroke
				(width 0.1)
				(type default)
			)
			(layer "B.Fab")
		)
		(fp_line
			(start 0.120605 0.304905)
			(end 0.679568 0.304811)
			(stroke
				(width 0.1)
				(type default)
			)
			(layer "B.Fab")
		)
		(fp_line
			(start 0.120554 0.279418)
			(end 0.120605 0.304905)
			(stroke
				(width 0.1)
				(type default)
			)
			(layer "B.Fab")
		)
		(fp_line
			(start -0.120316 0.304686)
			(end -0.12024 0.279419)
			(stroke
				(width 0.1)
				(type default)
			)
			(layer "B.Fab")
		)
		(fp_line
			(start -0.12024 0.279419)
			(end 0.120554 0.279418)
			(stroke
				(width 0.1)
				(type default)
			)
			(layer "B.Fab")
		)
		(fp_line
			(start 0.679373 -0.305128)
			(end 0.120629 -0.30516)
			(stroke
				(width 0.1)
				(type default)
			)
			(layer "B.Fab")
		)
		(fp_line
			(start -0.6795 0.304908)
			(end -0.120316 0.304686)
			(stroke
				(width 0.1)
				(type default)
			)
			(layer "B.Fab")
		)
		(fp_line
			(start 0.120587 -0.279326)
			(end -0.120554 -0.279418)
			(stroke
				(width 0.1)
				(type default)
			)
			(layer "B.Fab")
		)
		(fp_line
			(start 0.120629 -0.30516)
			(end 0.120587 -0.279326)
			(stroke
				(width 0.1)
				(type default)
			)
			(layer "B.Fab")
		)
		(fp_line
			(start -0.120554 -0.279418)
			(end -0.120605 -0.304905)
			(stroke
				(width 0.1)
				(type default)
			)
			(layer "B.Fab")
		)
		(fp_line
			(start -0.120605 -0.304905)
			(end -0.679568 -0.304811)
			(stroke
				(width 0.1)
				(type default)
			)
			(layer "B.Fab")
		)
		(fp_line
			(start -0.679568 -0.304811)
			(end -0.6795 0.304908)
			(stroke
				(width 0.1)
				(type default)
			)
			(layer "B.Fab")
		)
		(pad "1" smd circle
			(at 0.40005 0 60)
			(size 0 0)
			(layers "B.Cu" "B.Mask" "B.Paste")
			(net "PVDDCR_CPU0_P0")
		)
		(pad "2" smd circle
			(at -0.40005 0 60)
			(size 0 0)
			(layers "B.Cu" "B.Mask" "B.Paste")
			(net "GND")
		)
	)
	(footprint ""
		(layer "B.Cu")
		(at 183.294528 -425.674282 -90)
		(property "Reference" "R6232"
			(at 0 0 90)
			(layer "B.SilkS")
			(hide yes)
			(effects
				(font
					(size 1.27 1.27)
				)
				(justify mirror)
			)
		)
		(property "Value" ""
			(at 0 0 90)
			(layer "B.Fab")
			(effects
				(font
					(size 1.27 1.27)
				)
				(justify mirror)
			)
		)
		(duplicate_pad_numbers_are_jumpers no)
		(fp_line
			(start -0.7874 0.4064)
			(end 0.7874 0.4064)
			(stroke
				(width 0.1524)
				(type default)
			)
			(layer "B.SilkS")
		)
		(fp_line
			(start 0.7874 0.4064)
			(end 0.7874 -0.4064)
			(stroke
				(width 0.1524)
				(type default)
			)
			(layer "B.SilkS")
		)
		(fp_line
			(start -0.7874 -0.4064)
			(end -0.7874 0.4064)
			(stroke
				(width 0.1524)
				(type default)
			)
			(layer "B.SilkS")
		)
		(fp_line
			(start 0.7874 -0.4064)
			(end -0.7874 -0.4064)
			(stroke
				(width 0.1524)
				(type default)
			)
			(layer "B.SilkS")
		)
		(fp_line
			(start -0.67945 0.3048)
			(end -0.120396 0.3048)
			(stroke
				(width 0.1)
				(type default)
			)
			(layer "B.Fab")
		)
		(fp_line
			(start -0.120396 0.3048)
			(end -0.120396 0.2794)
			(stroke
				(width 0.1)
				(type default)
			)
			(layer "B.Fab")
		)
		(fp_line
			(start 0.12065 0.3048)
			(end 0.67945 0.3048)
			(stroke
				(width 0.1)
				(type default)
			)
			(layer "B.Fab")
		)
		(fp_line
			(start 0.67945 0.3048)
			(end 0.67945 -0.305054)
			(stroke
				(width 0.1)
				(type default)
			)
			(layer "B.Fab")
		)
		(fp_line
			(start -0.120396 0.2794)
			(end 0.12065 0.2794)
			(stroke
				(width 0.1)
				(type default)
			)
			(layer "B.Fab")
		)
		(fp_line
			(start 0.12065 0.2794)
			(end 0.12065 0.3048)
			(stroke
				(width 0.1)
				(type default)
			)
			(layer "B.Fab")
		)
		(fp_line
			(start -0.12065 -0.2794)
			(end -0.12065 -0.3048)
			(stroke
				(width 0.1)
				(type default)
			)
			(layer "B.Fab")
		)
		(fp_line
			(start 0.12065 -0.2794)
			(end -0.12065 -0.2794)
			(stroke
				(width 0.1)
				(type default)
			)
			(layer "B.Fab")
		)
		(fp_line
			(start -0.67945 -0.3048)
			(end -0.67945 0.3048)
			(stroke
				(width 0.1)
				(type default)
			)
			(layer "B.Fab")
		)
		(fp_line
			(start -0.12065 -0.3048)
			(end -0.67945 -0.3048)
			(stroke
				(width 0.1)
				(type default)
			)
			(layer "B.Fab")
		)
		(fp_line
			(start 0.12065 -0.305054)
			(end 0.12065 -0.2794)
			(stroke
				(width 0.1)
				(type default)
			)
			(layer "B.Fab")
		)
		(fp_line
			(start 0.67945 -0.305054)
			(end 0.12065 -0.305054)
			(stroke
				(width 0.1)
				(type default)
			)
			(layer "B.Fab")
		)
		(pad "1" smd circle
			(at 0.40005 0 90)
			(size 0 0)
			(layers "B.Cu" "B.Mask" "B.Paste")
			(net "HSC_CSOUT")
		)
		(pad "2" smd circle
			(at -0.40005 0 90)
			(size 0 0)
			(layers "B.Cu" "B.Mask" "B.Paste")
			(net "A_HSC_LOW")
		)
	)
	(footprint ""
		(layer "B.Cu")
		(at 379.888496 -178.977798 90)
		(property "Reference" "PC554_3"
			(at 0 0 90)
			(layer "B.SilkS")
			(hide yes)
			(effects
				(font
					(size 1.27 1.27)
				)
				(justify mirror)
			)
		)
		(property "Value" ""
			(at 0 0 90)
			(layer "B.Fab")
			(effects
				(font
					(size 1.27 1.27)
				)
				(justify mirror)
			)
		)
		(duplicate_pad_numbers_are_jumpers no)
		(fp_line
			(start 1.524 -0.762)
			(end -1.524 -0.762)
			(stroke
				(width 0.1524)
				(type default)
			)
			(layer "B.SilkS")
		)
		(fp_line
			(start -1.524 -0.762)
			(end -1.524 0.762)
			(stroke
				(width 0.1524)
				(type default)
			)
			(layer "B.SilkS")
		)
		(fp_line
			(start 1.524 0.762)
			(end 1.524 -0.762)
			(stroke
				(width 0.1524)
				(type default)
			)
			(layer "B.SilkS")
		)
		(fp_line
			(start -1.524 0.762)
			(end 1.524 0.762)
			(stroke
				(width 0.1524)
				(type default)
			)
			(layer "B.SilkS")
		)
		(fp_line
			(start 1.1049 -0.724916)
			(end 1.1049 0.724916)
			(stroke
				(width 0.1)
				(type default)
			)
			(layer "B.Fab")
		)
		(fp_line
			(start -1.1049 -0.724916)
			(end 1.1049 -0.724916)
			(stroke
				(width 0.1)
				(type default)
			)
			(layer "B.Fab")
		)
		(fp_line
			(start 1.1049 0.724916)
			(end -1.1049 0.724916)
			(stroke
				(width 0.1)
				(type default)
			)
			(layer "B.Fab")
		)
		(fp_line
			(start -1.1049 0.724916)
			(end -1.1049 -0.724916)
			(stroke
				(width 0.1)
				(type default)
			)
			(layer "B.Fab")
		)
		(pad "1" smd rect
			(at 0.889 0 90)
			(size 1.016 1.27)
			(layers "B.Cu" "B.Mask" "B.Paste")
			(net "SW_P12V_AUX_PVDDCR_CPU0_P0_FLT")
		)
		(pad "2" smd rect
			(at -0.889 0 90)
			(size 1.016 1.27)
			(layers "B.Cu" "B.Mask" "B.Paste")
			(net "GND")
		)
	)
	(footprint ""
		(layer "B.Cu")
		(at 142.04061 -388.846568)
		(property "Reference" "C409"
			(at 0 0 0)
			(layer "B.SilkS")
			(hide yes)
			(effects
				(font
					(size 1.27 1.27)
				)
				(justify mirror)
			)
		)
		(property "Value" ""
			(at 0 0 0)
			(layer "B.Fab")
			(effects
				(font
					(size 1.27 1.27)
				)
				(justify mirror)
			)
		)
		(duplicate_pad_numbers_are_jumpers no)
		(fp_line
			(start -1.524 -0.762)
			(end -1.524 0.762)
			(stroke
				(width 0.1524)
				(type default)
			)
			(layer "B.SilkS")
		)
		(fp_line
			(start -1.524 0.762)
			(end 1.524 0.762)
			(stroke
				(width 0.1524)
				(type default)
			)
			(layer "B.SilkS")
		)
		(fp_line
			(start 1.524 -0.762)
			(end -1.524 -0.762)
			(stroke
				(width 0.1524)
				(type default)
			)
			(layer "B.SilkS")
		)
		(fp_line
			(start 1.524 0.762)
			(end 1.524 -0.762)
			(stroke
				(width 0.1524)
				(type default)
			)
			(layer "B.SilkS")
		)
		(fp_line
			(start -1.1049 -0.724916)
			(end 1.1049 -0.724916)
			(stroke
				(width 0.1)
				(type default)
			)
			(layer "B.Fab")
		)
		(fp_line
			(start -1.1049 0.724916)
			(end -1.1049 -0.724916)
			(stroke
				(width 0.1)
				(type default)
			)
			(layer "B.Fab")
		)
		(fp_line
			(start 1.1049 -0.724916)
			(end 1.1049 0.724916)
			(stroke
				(width 0.1)
				(type default)
			)
			(layer "B.Fab")
		)
		(fp_line
			(start 1.1049 0.724916)
			(end -1.1049 0.724916)
			(stroke
				(width 0.1)
				(type default)
			)
			(layer "B.Fab")
		)
		(pad "1" smd rect
			(at 0.889 0)
			(size 1.016 1.27)
			(layers "B.Cu" "B.Mask" "B.Paste")
			(net "P0V9_CPU1_RT2_2A")
		)
		(pad "2" smd rect
			(at -0.889 0)
			(size 1.016 1.27)
			(layers "B.Cu" "B.Mask" "B.Paste")
			(net "GND")
		)
	)
	(footprint ""
		(layer "B.Cu")
		(at 106.68 -417.322 90)
		(property "Reference" "Q74"
			(at -3.683 -0.28067 270)
			(unlocked yes)
			(layer "B.SilkS")
			(effects
				(font
					(size 0.7874 0.5842)
					(thickness 0.1524)
				)
				(justify left mirror)
			)
		)
		(property "Value" ""
			(at 0 0 90)
			(layer "B.Fab")
			(effects
				(font
					(size 1.27 1.27)
				)
				(justify mirror)
			)
		)
		(duplicate_pad_numbers_are_jumpers no)
		(fp_line
			(start 1.332738 -1.100074)
			(end 0.4826 -1.100074)
			(stroke
				(width 0.1524)
				(type default)
			)
			(layer "B.SilkS")
		)
		(fp_line
			(start 0.4826 -1.100074)
			(end 0 -0.541274)
			(stroke
				(width 0.1524)
				(type default)
			)
			(layer "B.SilkS")
		)
		(fp_line
			(start -0.4826 -1.100074)
			(end -1.332738 -1.100074)
			(stroke
				(width 0.1524)
				(type default)
			)
			(layer "B.SilkS")
		)
		(fp_line
			(start -1.332738 -1.100074)
			(end -1.332738 1.100074)
			(stroke
				(width 0.1524)
				(type default)
			)
			(layer "B.SilkS")
		)
		(fp_line
			(start 0 -0.541274)
			(end -0.4826 -1.100074)
			(stroke
				(width 0.1524)
				(type default)
			)
			(layer "B.SilkS")
		)
		(fp_line
			(start 1.332738 1.100074)
			(end 1.332738 -1.100074)
			(stroke
				(width 0.1524)
				(type default)
			)
			(layer "B.SilkS")
		)
		(fp_line
			(start -1.332738 1.100074)
			(end 1.332738 1.100074)
			(stroke
				(width 0.1524)
				(type default)
			)
			(layer "B.SilkS")
		)
		(fp_poly
			(pts
				(xy 1.441196 -0.658876) (xy 2.143252 -0.307848) (xy 2.143252 -1.009904)
			)
			(stroke
				(width 0)
				(type default)
			)
			(fill yes)
			(layer "B.SilkS")
		)
		(fp_line
			(start 0.674878 -1.100074)
			(end -0.674878 -1.100074)
			(stroke
				(width 0.1)
				(type default)
			)
			(layer "B.Fab")
		)
		(fp_line
			(start -0.674878 -1.100074)
			(end -0.674878 1.100074)
			(stroke
				(width 0.1)
				(type default)
			)
			(layer "B.Fab")
		)
		(fp_line
			(start 0.674878 1.100074)
			(end 0.674878 -1.100074)
			(stroke
				(width 0.1)
				(type default)
			)
			(layer "B.Fab")
		)
		(fp_line
			(start -0.674878 1.100074)
			(end 0.674878 1.100074)
			(stroke
				(width 0.1)
				(type default)
			)
			(layer "B.Fab")
		)
		(fp_poly
			(pts
				(xy 2.2352 -0.298958) (xy 2.2352 -1.001014) (xy 1.533144 -0.649986)
			)
			(stroke
				(width 0)
				(type default)
			)
			(fill yes)
			(layer "B.Fab")
		)
		(pad "1" smd rect
			(at 0.94996 -0.649986 180)
			(size 0.4318 0.508)
			(layers "B.Cu" "B.Mask" "B.Paste")
			(net "GND")
		)
		(pad "2" smd rect
			(at 0.94996 0 180)
			(size 0.4318 0.508)
			(layers "B.Cu" "B.Mask" "B.Paste")
			(net "FM_SMB_2_ALERT_GPU_N")
		)
		(pad "3" smd rect
			(at 0.94996 0.649986 180)
			(size 0.4318 0.508)
			(layers "B.Cu" "B.Mask" "B.Paste")
			(net "FM_SMB_2_ALERT_GPU_ISO_N")
		)
		(pad "4" smd rect
			(at -0.94996 0.649986 180)
			(size 0.4318 0.508)
			(layers "B.Cu" "B.Mask" "B.Paste")
			(net "GND")
		)
		(pad "5" smd rect
			(at -0.94996 0 180)
			(size 0.4318 0.508)
			(layers "B.Cu" "B.Mask" "B.Paste")
			(net "FM_SMB_2_ALERT_GPU")
		)
		(pad "6" smd rect
			(at -0.94996 -0.649986 180)
			(size 0.4318 0.508)
			(layers "B.Cu" "B.Mask" "B.Paste")
			(net "FM_SMB_2_ALERT_GPU")
		)
	)
	(footprint ""
		(layer "B.Cu")
		(at 90.846148 -388.011162 -90)
		(property "Reference" "C206"
			(at 0 0 90)
			(layer "B.SilkS")
			(hide yes)
			(effects
				(font
					(size 1.27 1.27)
				)
				(justify mirror)
			)
		)
		(property "Value" ""
			(at 0 0 90)
			(layer "B.Fab")
			(effects
				(font
					(size 1.27 1.27)
				)
				(justify mirror)
			)
		)
		(duplicate_pad_numbers_are_jumpers no)
		(fp_line
			(start -0.299974 0.150114)
			(end 0.299974 0.150114)
			(stroke
				(width 0.1)
				(type default)
			)
			(layer "B.Fab")
		)
		(fp_line
			(start 0.299974 0.150114)
			(end 0.299974 -0.150114)
			(stroke
				(width 0.1)
				(type default)
			)
			(layer "B.Fab")
		)
		(fp_line
			(start -0.299974 -0.150114)
			(end -0.299974 0.150114)
			(stroke
				(width 0.1)
				(type default)
			)
			(layer "B.Fab")
		)
		(fp_line
			(start 0.299974 -0.150114)
			(end -0.299974 -0.150114)
			(stroke
				(width 0.1)
				(type default)
			)
			(layer "B.Fab")
		)
		(pad "1" smd rect
			(at 0.2667 0 90)
			(size 0.3048 0.381)
			(layers "B.Cu" "B.Mask" "B.Paste")
			(net "P1V8_CPU1_RT1_1A_1D")
		)
		(pad "2" smd rect
			(at -0.2667 0 90)
			(size 0.3048 0.381)
			(layers "B.Cu" "B.Mask" "B.Paste")
			(net "GND")
		)
	)
	(footprint ""
		(layer "B.Cu")
		(at 324.593966 -416.899344 90)
		(property "Reference" "C6545"
			(at 0 0 90)
			(layer "B.SilkS")
			(hide yes)
			(effects
				(font
					(size 1.27 1.27)
				)
				(justify mirror)
			)
		)
		(property "Value" ""
			(at 0 0 90)
			(layer "B.Fab")
			(effects
				(font
					(size 1.27 1.27)
				)
				(justify mirror)
			)
		)
		(duplicate_pad_numbers_are_jumpers no)
		(fp_line
			(start 0.299974 -0.150114)
			(end -0.299974 -0.150114)
			(stroke
				(width 0.1)
				(type default)
			)
			(layer "B.Fab")
		)
		(fp_line
			(start -0.299974 -0.150114)
			(end -0.299974 0.150114)
			(stroke
				(width 0.1)
				(type default)
			)
			(layer "B.Fab")
		)
		(fp_line
			(start 0.299974 0.150114)
			(end 0.299974 -0.150114)
			(stroke
				(width 0.1)
				(type default)
			)
			(layer "B.Fab")
		)
		(fp_line
			(start -0.299974 0.150114)
			(end 0.299974 0.150114)
			(stroke
				(width 0.1)
				(type default)
			)
			(layer "B.Fab")
		)
		(pad "1" smd rect
			(at 0.2667 0 270)
			(size 0.3048 0.381)
			(layers "B.Cu" "B.Mask" "B.Paste")
			(net "P5E_CPU0_P1_TX_BUF_C_DP<6>")
		)
		(pad "2" smd rect
			(at -0.2667 0 270)
			(size 0.3048 0.381)
			(layers "B.Cu" "B.Mask" "B.Paste")
			(net "P5E_CPU0_P1_TX_BUF_DP<6>")
		)
	)
)
